(kicad_pcb
	(version 20260206)
	(generator "pcbnew")
	(generator_version "10.0")
	(general
		(thickness 1.6)
		(legacy_teardrops no)
	)
	(paper "A4")
	(title_block
		(title "01162023_DA0F0TEBIF0_F0T_Expander_BD_F_brd_V02_OCP.brd")
		(comment 1 "Grand Teton / footprints 2780-2785 of 9728")
	)
	(layers
		(0 "F.Cu" signal "TOP")
		(4 "In1.Cu" signal "GND")
		(6 "In2.Cu" signal "VCC")
		(8 "In3.Cu" signal "VCC1")
		(10 "In4.Cu" signal "GND1")
		(12 "In5.Cu" signal "IN1")
		(14 "In6.Cu" signal "GND2")
		(16 "In7.Cu" signal "IN2")
		(18 "In8.Cu" signal "GND3")
		(20 "In9.Cu" signal "IN3")
		(22 "In10.Cu" signal "GND4")
		(24 "In11.Cu" signal "IN4")
		(26 "In12.Cu" signal "GND5")
		(28 "In13.Cu" signal "IN5")
		(30 "In14.Cu" signal "GND6")
		(32 "In15.Cu" signal "IN6")
		(34 "In16.Cu" signal "GND7")
		(2 "B.Cu" signal "BOTTOM")
		(9 "F.Adhes" user "F.Adhesive")
		(11 "B.Adhes" user "B.Adhesive")
		(13 "F.Paste" user "Package Geometry/Pastemask Top")
		(15 "B.Paste" user "Package Geometry/Pastemask Bottom")
		(5 "F.SilkS" user "Ref Des/Silkscreen Top")
		(7 "B.SilkS" user "Ref Des/Silkscreen Bottom")
		(1 "F.Mask" user "Board Geometry/Soldermask Top")
		(3 "B.Mask" user "Board Geometry/Soldermask Bottom")
		(17 "Dwgs.User" user "User.Drawings")
		(19 "Cmts.User" user "User.Comments")
		(21 "Eco1.User" user "User.Eco1")
		(23 "Eco2.User" user "User.Eco2")
		(25 "Edge.Cuts" user "Board Geometry/Outline")
		(27 "Margin" user)
		(31 "F.CrtYd" user "Package Geometry/Place Bound Top")
		(29 "B.CrtYd" user "Package Geometry/Place Bound Bottom")
		(35 "F.Fab" user "Ref Des/Assembly Top")
		(33 "B.Fab" user "Ref Des/Assembly Bottom")
	)
	(footprint ""
		(layer "F.Cu")
		(at 284.467808 -55.083456)
		(property "Reference" "PC444"
			(at 0 0 0)
			(layer "F.SilkS")
			(hide yes)
			(effects
				(font
					(size 1.27 1.27)
				)
			)
		)
		(property "Value" ""
			(at 0 0 0)
			(layer "F.Fab")
			(effects
				(font
					(size 1.27 1.27)
				)
			)
		)
		(duplicate_pad_numbers_are_jumpers no)
		(fp_line
			(start -0.7874 -0.4064)
			(end 0.7874 -0.4064)
			(stroke
				(width 0.1524)
				(type default)
			)
			(layer "F.SilkS")
		)
		(fp_line
			(start -0.7874 0.4064)
			(end -0.7874 -0.4064)
			(stroke
				(width 0.1524)
				(type default)
			)
			(layer "F.SilkS")
		)
		(fp_line
			(start 0.7874 -0.4064)
			(end 0.7874 0.4064)
			(stroke
				(width 0.1524)
				(type default)
			)
			(layer "F.SilkS")
		)
		(fp_line
			(start 0.7874 0.4064)
			(end -0.7874 0.4064)
			(stroke
				(width 0.1524)
				(type default)
			)
			(layer "F.SilkS")
		)
		(fp_line
			(start -0.67945 -0.305054)
			(end -0.12065 -0.305054)
			(stroke
				(width 0.1)
				(type default)
			)
			(layer "F.Fab")
		)
		(fp_line
			(start -0.67945 0.3048)
			(end -0.67945 -0.305054)
			(stroke
				(width 0.1)
				(type default)
			)
			(layer "F.Fab")
		)
		(fp_line
			(start -0.12065 -0.305054)
			(end -0.12065 -0.2794)
			(stroke
				(width 0.1)
				(type default)
			)
			(layer "F.Fab")
		)
		(fp_line
			(start -0.12065 -0.2794)
			(end 0.12065 -0.2794)
			(stroke
				(width 0.1)
				(type default)
			)
			(layer "F.Fab")
		)
		(fp_line
			(start -0.12065 0.2794)
			(end -0.12065 0.3048)
			(stroke
				(width 0.1)
				(type default)
			)
			(layer "F.Fab")
		)
		(fp_line
			(start -0.12065 0.3048)
			(end -0.67945 0.3048)
			(stroke
				(width 0.1)
				(type default)
			)
			(layer "F.Fab")
		)
		(fp_line
			(start 0.120396 0.2794)
			(end -0.12065 0.2794)
			(stroke
				(width 0.1)
				(type default)
			)
			(layer "F.Fab")
		)
		(fp_line
			(start 0.120396 0.3048)
			(end 0.120396 0.2794)
			(stroke
				(width 0.1)
				(type default)
			)
			(layer "F.Fab")
		)
		(fp_line
			(start 0.12065 -0.3048)
			(end 0.67945 -0.3048)
			(stroke
				(width 0.1)
				(type default)
			)
			(layer "F.Fab")
		)
		(fp_line
			(start 0.12065 -0.2794)
			(end 0.12065 -0.3048)
			(stroke
				(width 0.1)
				(type default)
			)
			(layer "F.Fab")
		)
		(fp_line
			(start 0.67945 -0.3048)
			(end 0.67945 0.3048)
			(stroke
				(width 0.1)
				(type default)
			)
			(layer "F.Fab")
		)
		(fp_line
			(start 0.67945 0.3048)
			(end 0.120396 0.3048)
			(stroke
				(width 0.1)
				(type default)
			)
			(layer "F.Fab")
		)
		(pad "1" smd circle
			(at -0.40005 0)
			(size 0 0)
			(layers "F.Cu" "F.Mask" "F.Paste")
			(net "P5V_AUX")
		)
		(pad "2" smd circle
			(at 0.40005 0)
			(size 0 0)
			(layers "F.Cu" "F.Mask" "F.Paste")
			(net "GND")
		)
	)
	(footprint ""
		(layer "F.Cu")
		(at 6.196584 -14.04747 180)
		(property "Reference" "C3875"
			(at 0 0 180)
			(layer "F.SilkS")
			(hide yes)
			(effects
				(font
					(size 1.27 1.27)
				)
			)
		)
		(property "Value" ""
			(at 0 0 180)
			(layer "F.Fab")
			(effects
				(font
					(size 1.27 1.27)
				)
			)
		)
		(duplicate_pad_numbers_are_jumpers no)
		(fp_line
			(start 0.7874 0.4064)
			(end -0.7874 0.4064)
			(stroke
				(width 0.1524)
				(type default)
			)
			(layer "F.SilkS")
		)
		(fp_line
			(start 0.7874 -0.4064)
			(end 0.7874 0.4064)
			(stroke
				(width 0.1524)
				(type default)
			)
			(layer "F.SilkS")
		)
		(fp_line
			(start -0.7874 0.4064)
			(end -0.7874 -0.4064)
			(stroke
				(width 0.1524)
				(type default)
			)
			(layer "F.SilkS")
		)
		(fp_line
			(start -0.7874 -0.4064)
			(end 0.7874 -0.4064)
			(stroke
				(width 0.1524)
				(type default)
			)
			(layer "F.SilkS")
		)
		(fp_line
			(start 0.67945 0.3048)
			(end 0.120396 0.3048)
			(stroke
				(width 0.1)
				(type default)
			)
			(layer "F.Fab")
		)
		(fp_line
			(start 0.67945 -0.3048)
			(end 0.67945 0.3048)
			(stroke
				(width 0.1)
				(type default)
			)
			(layer "F.Fab")
		)
		(fp_line
			(start 0.12065 -0.2794)
			(end 0.12065 -0.3048)
			(stroke
				(width 0.1)
				(type default)
			)
			(layer "F.Fab")
		)
		(fp_line
			(start 0.12065 -0.3048)
			(end 0.67945 -0.3048)
			(stroke
				(width 0.1)
				(type default)
			)
			(layer "F.Fab")
		)
		(fp_line
			(start 0.120396 0.3048)
			(end 0.120396 0.2794)
			(stroke
				(width 0.1)
				(type default)
			)
			(layer "F.Fab")
		)
		(fp_line
			(start 0.120396 0.2794)
			(end -0.12065 0.2794)
			(stroke
				(width 0.1)
				(type default)
			)
			(layer "F.Fab")
		)
		(fp_line
			(start -0.12065 0.3048)
			(end -0.67945 0.3048)
			(stroke
				(width 0.1)
				(type default)
			)
			(layer "F.Fab")
		)
		(fp_line
			(start -0.12065 0.2794)
			(end -0.12065 0.3048)
			(stroke
				(width 0.1)
				(type default)
			)
			(layer "F.Fab")
		)
		(fp_line
			(start -0.12065 -0.2794)
			(end 0.12065 -0.2794)
			(stroke
				(width 0.1)
				(type default)
			)
			(layer "F.Fab")
		)
		(fp_line
			(start -0.12065 -0.305054)
			(end -0.12065 -0.2794)
			(stroke
				(width 0.1)
				(type default)
			)
			(layer "F.Fab")
		)
		(fp_line
			(start -0.67945 0.3048)
			(end -0.67945 -0.305054)
			(stroke
				(width 0.1)
				(type default)
			)
			(layer "F.Fab")
		)
		(fp_line
			(start -0.67945 -0.305054)
			(end -0.12065 -0.305054)
			(stroke
				(width 0.1)
				(type default)
			)
			(layer "F.Fab")
		)
		(pad "1" smd circle
			(at -0.40005 0 180)
			(size 0 0)
			(layers "F.Cu" "F.Mask" "F.Paste")
			(net "P12V_SSD0")
		)
		(pad "2" smd circle
			(at 0.40005 0 180)
			(size 0 0)
			(layers "F.Cu" "F.Mask" "F.Paste")
			(net "GND")
		)
	)
	(footprint ""
		(layer "F.Cu")
		(at 327.533 -213.233 180)
		(property "Reference" "R4154"
			(at 0 0 180)
			(layer "F.SilkS")
			(hide yes)
			(effects
				(font
					(size 1.27 1.27)
				)
			)
		)
		(property "Value" ""
			(at 0 0 180)
			(layer "F.Fab")
			(effects
				(font
					(size 1.27 1.27)
				)
			)
		)
		(duplicate_pad_numbers_are_jumpers no)
		(fp_line
			(start 0.7874 0.4064)
			(end -0.7874 0.4064)
			(stroke
				(width 0.1524)
				(type default)
			)
			(layer "F.SilkS")
		)
		(fp_line
			(start 0.7874 -0.4064)
			(end 0.7874 0.4064)
			(stroke
				(width 0.1524)
				(type default)
			)
			(layer "F.SilkS")
		)
		(fp_line
			(start -0.7874 0.4064)
			(end -0.7874 -0.4064)
			(stroke
				(width 0.1524)
				(type default)
			)
			(layer "F.SilkS")
		)
		(fp_line
			(start -0.7874 -0.4064)
			(end 0.7874 -0.4064)
			(stroke
				(width 0.1524)
				(type default)
			)
			(layer "F.SilkS")
		)
		(fp_line
			(start 0.67945 0.3048)
			(end 0.120396 0.3048)
			(stroke
				(width 0.1)
				(type default)
			)
			(layer "F.Fab")
		)
		(fp_line
			(start 0.67945 -0.3048)
			(end 0.67945 0.3048)
			(stroke
				(width 0.1)
				(type default)
			)
			(layer "F.Fab")
		)
		(fp_line
			(start 0.12065 -0.2794)
			(end 0.12065 -0.3048)
			(stroke
				(width 0.1)
				(type default)
			)
			(layer "F.Fab")
		)
		(fp_line
			(start 0.12065 -0.3048)
			(end 0.67945 -0.3048)
			(stroke
				(width 0.1)
				(type default)
			)
			(layer "F.Fab")
		)
		(fp_line
			(start 0.120396 0.3048)
			(end 0.120396 0.2794)
			(stroke
				(width 0.1)
				(type default)
			)
			(layer "F.Fab")
		)
		(fp_line
			(start 0.120396 0.2794)
			(end -0.12065 0.2794)
			(stroke
				(width 0.1)
				(type default)
			)
			(layer "F.Fab")
		)
		(fp_line
			(start -0.12065 0.3048)
			(end -0.67945 0.3048)
			(stroke
				(width 0.1)
				(type default)
			)
			(layer "F.Fab")
		)
		(fp_line
			(start -0.12065 0.2794)
			(end -0.12065 0.3048)
			(stroke
				(width 0.1)
				(type default)
			)
			(layer "F.Fab")
		)
		(fp_line
			(start -0.12065 -0.2794)
			(end 0.12065 -0.2794)
			(stroke
				(width 0.1)
				(type default)
			)
			(layer "F.Fab")
		)
		(fp_line
			(start -0.12065 -0.305054)
			(end -0.12065 -0.2794)
			(stroke
				(width 0.1)
				(type default)
			)
			(layer "F.Fab")
		)
		(fp_line
			(start -0.67945 0.3048)
			(end -0.67945 -0.305054)
			(stroke
				(width 0.1)
				(type default)
			)
			(layer "F.Fab")
		)
		(fp_line
			(start -0.67945 -0.305054)
			(end -0.12065 -0.305054)
			(stroke
				(width 0.1)
				(type default)
			)
			(layer "F.Fab")
		)
		(pad "1" smd circle
			(at -0.40005 0 180)
			(size 0 0)
			(layers "F.Cu" "F.Mask" "F.Paste")
			(net "PRSNT_SSD7_FPGA_N")
		)
		(pad "2" smd circle
			(at 0.40005 0 180)
			(size 0 0)
			(layers "F.Cu" "F.Mask" "F.Paste")
			(net "PRSNT_SSD7_FPGA_R_N")
		)
	)
	(footprint ""
		(layer "F.Cu")
		(at 338.074 -170.053 180)
		(property "Reference" "R4769"
			(at 0 0 180)
			(layer "F.SilkS")
			(hide yes)
			(effects
				(font
					(size 1.27 1.27)
				)
			)
		)
		(property "Value" ""
			(at 0 0 180)
			(layer "F.Fab")
			(effects
				(font
					(size 1.27 1.27)
				)
			)
		)
		(duplicate_pad_numbers_are_jumpers no)
		(fp_line
			(start 0.7874 0.4064)
			(end -0.7874 0.4064)
			(stroke
				(width 0.1524)
				(type default)
			)
			(layer "F.SilkS")
		)
		(fp_line
			(start 0.7874 -0.4064)
			(end 0.7874 0.4064)
			(stroke
				(width 0.1524)
				(type default)
			)
			(layer "F.SilkS")
		)
		(fp_line
			(start -0.7874 0.4064)
			(end -0.7874 -0.4064)
			(stroke
				(width 0.1524)
				(type default)
			)
			(layer "F.SilkS")
		)
		(fp_line
			(start -0.7874 -0.4064)
			(end 0.7874 -0.4064)
			(stroke
				(width 0.1524)
				(type default)
			)
			(layer "F.SilkS")
		)
		(fp_line
			(start 0.67945 0.3048)
			(end 0.120396 0.3048)
			(stroke
				(width 0.1)
				(type default)
			)
			(layer "F.Fab")
		)
		(fp_line
			(start 0.67945 -0.3048)
			(end 0.67945 0.3048)
			(stroke
				(width 0.1)
				(type default)
			)
			(layer "F.Fab")
		)
		(fp_line
			(start 0.12065 -0.2794)
			(end 0.12065 -0.3048)
			(stroke
				(width 0.1)
				(type default)
			)
			(layer "F.Fab")
		)
		(fp_line
			(start 0.12065 -0.3048)
			(end 0.67945 -0.3048)
			(stroke
				(width 0.1)
				(type default)
			)
			(layer "F.Fab")
		)
		(fp_line
			(start 0.120396 0.3048)
			(end 0.120396 0.2794)
			(stroke
				(width 0.1)
				(type default)
			)
			(layer "F.Fab")
		)
		(fp_line
			(start 0.120396 0.2794)
			(end -0.12065 0.2794)
			(stroke
				(width 0.1)
				(type default)
			)
			(layer "F.Fab")
		)
		(fp_line
			(start -0.12065 0.3048)
			(end -0.67945 0.3048)
			(stroke
				(width 0.1)
				(type default)
			)
			(layer "F.Fab")
		)
		(fp_line
			(start -0.12065 0.2794)
			(end -0.12065 0.3048)
			(stroke
				(width 0.1)
				(type default)
			)
			(layer "F.Fab")
		)
		(fp_line
			(start -0.12065 -0.2794)
			(end 0.12065 -0.2794)
			(stroke
				(width 0.1)
				(type default)
			)
			(layer "F.Fab")
		)
		(fp_line
			(start -0.12065 -0.305054)
			(end -0.12065 -0.2794)
			(stroke
				(width 0.1)
				(type default)
			)
			(layer "F.Fab")
		)
		(fp_line
			(start -0.67945 0.3048)
			(end -0.67945 -0.305054)
			(stroke
				(width 0.1)
				(type default)
			)
			(layer "F.Fab")
		)
		(fp_line
			(start -0.67945 -0.305054)
			(end -0.12065 -0.305054)
			(stroke
				(width 0.1)
				(type default)
			)
			(layer "F.Fab")
		)
		(pad "1" smd circle
			(at -0.40005 0 180)
			(size 0 0)
			(layers "F.Cu" "F.Mask" "F.Paste")
			(net "SSD10_PEX_PWR_EN")
		)
		(pad "2" smd circle
			(at 0.40005 0 180)
			(size 0 0)
			(layers "F.Cu" "F.Mask" "F.Paste")
			(net "SSD10_PEX_PWR_EN_R")
		)
	)
	(footprint ""
		(layer "F.Cu")
		(at 353.822 -179.578)
		(property "Reference" "R4759"
			(at 0 0 0)
			(layer "F.SilkS")
			(hide yes)
			(effects
				(font
					(size 1.27 1.27)
				)
			)
		)
		(property "Value" ""
			(at 0 0 0)
			(layer "F.Fab")
			(effects
				(font
					(size 1.27 1.27)
				)
			)
		)
		(duplicate_pad_numbers_are_jumpers no)
		(fp_line
			(start -0.7874 -0.4064)
			(end 0.7874 -0.4064)
			(stroke
				(width 0.1524)
				(type default)
			)
			(layer "F.SilkS")
		)
		(fp_line
			(start -0.7874 0.4064)
			(end -0.7874 -0.4064)
			(stroke
				(width 0.1524)
				(type default)
			)
			(layer "F.SilkS")
		)
		(fp_line
			(start 0.7874 -0.4064)
			(end 0.7874 0.4064)
			(stroke
				(width 0.1524)
				(type default)
			)
			(layer "F.SilkS")
		)
		(fp_line
			(start 0.7874 0.4064)
			(end -0.7874 0.4064)
			(stroke
				(width 0.1524)
				(type default)
			)
			(layer "F.SilkS")
		)
		(fp_line
			(start -0.67945 -0.305054)
			(end -0.12065 -0.305054)
			(stroke
				(width 0.1)
				(type default)
			)
			(layer "F.Fab")
		)
		(fp_line
			(start -0.67945 0.3048)
			(end -0.67945 -0.305054)
			(stroke
				(width 0.1)
				(type default)
			)
			(layer "F.Fab")
		)
		(fp_line
			(start -0.12065 -0.305054)
			(end -0.12065 -0.2794)
			(stroke
				(width 0.1)
				(type default)
			)
			(layer "F.Fab")
		)
		(fp_line
			(start -0.12065 -0.2794)
			(end 0.12065 -0.2794)
			(stroke
				(width 0.1)
				(type default)
			)
			(layer "F.Fab")
		)
		(fp_line
			(start -0.12065 0.2794)
			(end -0.12065 0.3048)
			(stroke
				(width 0.1)
				(type default)
			)
			(layer "F.Fab")
		)
		(fp_line
			(start -0.12065 0.3048)
			(end -0.67945 0.3048)
			(stroke
				(width 0.1)
				(type default)
			)
			(layer "F.Fab")
		)
		(fp_line
			(start 0.120396 0.2794)
			(end -0.12065 0.2794)
			(stroke
				(width 0.1)
				(type default)
			)
			(layer "F.Fab")
		)
		(fp_line
			(start 0.120396 0.3048)
			(end 0.120396 0.2794)
			(stroke
				(width 0.1)
				(type default)
			)
			(layer "F.Fab")
		)
		(fp_line
			(start 0.12065 -0.3048)
			(end 0.67945 -0.3048)
			(stroke
				(width 0.1)
				(type default)
			)
			(layer "F.Fab")
		)
		(fp_line
			(start 0.12065 -0.2794)
			(end 0.12065 -0.3048)
			(stroke
				(width 0.1)
				(type default)
			)
			(layer "F.Fab")
		)
		(fp_line
			(start 0.67945 -0.3048)
			(end 0.67945 0.3048)
			(stroke
				(width 0.1)
				(type default)
			)
			(layer "F.Fab")
		)
		(fp_line
			(start 0.67945 0.3048)
			(end 0.120396 0.3048)
			(stroke
				(width 0.1)
				(type default)
			)
			(layer "F.Fab")
		)
		(pad "1" smd circle
			(at -0.40005 0)
			(size 0 0)
			(layers "F.Cu" "F.Mask" "F.Paste")
			(net "RST_PEX_NIC4_PERST_N")
		)
		(pad "2" smd circle
			(at 0.40005 0)
			(size 0 0)
			(layers "F.Cu" "F.Mask" "F.Paste")
			(net "RST_PEX_NIC4_PERST_R_N")
		)
	)
	(footprint ""
		(layer "F.Cu")
		(at 326.007222 -235.075222 90)
		(property "Reference" "R4389"
			(at 0 0 90)
			(layer "F.SilkS")
			(hide yes)
			(effects
				(font
					(size 1.27 1.27)
				)
			)
		)
		(property "Value" ""
			(at 0 0 90)
			(layer "F.Fab")
			(effects
				(font
					(size 1.27 1.27)
				)
			)
		)
		(duplicate_pad_numbers_are_jumpers no)
		(fp_line
			(start 0.7874 -0.4064)
			(end 0.7874 0.4064)
			(stroke
				(width 0.1524)
				(type default)
			)
			(layer "F.SilkS")
		)
		(fp_line
			(start -0.7874 -0.4064)
			(end 0.7874 -0.4064)
			(stroke
				(width 0.1524)
				(type default)
			)
			(layer "F.SilkS")
		)
		(fp_line
			(start 0.7874 0.4064)
			(end -0.7874 0.4064)
			(stroke
				(width 0.1524)
				(type default)
			)
			(layer "F.SilkS")
		)
		(fp_line
			(start -0.7874 0.4064)
			(end -0.7874 -0.4064)
			(stroke
				(width 0.1524)
				(type default)
			)
			(layer "F.SilkS")
		)
		(fp_line
			(start -0.12065 -0.305054)
			(end -0.12065 -0.2794)
			(stroke
				(width 0.1)
				(type default)
			)
			(layer "F.Fab")
		)
		(fp_line
			(start -0.67945 -0.305054)
			(end -0.12065 -0.305054)
			(stroke
				(width 0.1)
				(type default)
			)
			(layer "F.Fab")
		)
		(fp_line
			(start 0.67945 -0.3048)
			(end 0.67945 0.3048)
			(stroke
				(width 0.1)
				(type default)
			)
			(layer "F.Fab")
		)
		(fp_line
			(start 0.12065 -0.3048)
			(end 0.67945 -0.3048)
			(stroke
				(width 0.1)
				(type default)
			)
			(layer "F.Fab")
		)
		(fp_line
			(start 0.12065 -0.2794)
			(end 0.12065 -0.3048)
			(stroke
				(width 0.1)
				(type default)
			)
			(layer "F.Fab")
		)
		(fp_line
			(start -0.12065 -0.2794)
			(end 0.12065 -0.2794)
			(stroke
				(width 0.1)
				(type default)
			)
			(layer "F.Fab")
		)
		(fp_line
			(start 0.120396 0.2794)
			(end -0.12065 0.2794)
			(stroke
				(width 0.1)
				(type default)
			)
			(layer "F.Fab")
		)
		(fp_line
			(start -0.12065 0.2794)
			(end -0.12065 0.3048)
			(stroke
				(width 0.1)
				(type default)
			)
			(layer "F.Fab")
		)
		(fp_line
			(start 0.67945 0.3048)
			(end 0.120396 0.3048)
			(stroke
				(width 0.1)
				(type default)
			)
			(layer "F.Fab")
		)
		(fp_line
			(start 0.120396 0.3048)
			(end 0.120396 0.2794)
			(stroke
				(width 0.1)
				(type default)
			)
			(layer "F.Fab")
		)
		(fp_line
			(start -0.12065 0.3048)
			(end -0.67945 0.3048)
			(stroke
				(width 0.1)
				(type default)
			)
			(layer "F.Fab")
		)
		(fp_line
			(start -0.67945 0.3048)
			(end -0.67945 -0.305054)
			(stroke
				(width 0.1)
				(type default)
			)
			(layer "F.Fab")
		)
		(pad "1" smd circle
			(at -0.40005 0 90)
			(size 0 0)
			(layers "F.Cu" "F.Mask" "F.Paste")
			(net "RST_PEX_SYS_BUF_R_N")
		)
		(pad "2" smd circle
			(at 0.40005 0 90)
			(size 0 0)
			(layers "F.Cu" "F.Mask" "F.Paste")
			(net "RST_PEX2_SYS_N")
		)
	)
)
